# T6G (Grand Teton) — schematic netlist excerpt (pin names and nets, part order shuffled) for the footprints in the layout excerpt that follows; sources: Cadence DE-HDL packaged netlist, KiCad conversion of 04192023_DAF0TMB3IC0_F0TG_MB_C_brd_V02_OCP.brd

R2919  Q_RES  100K 1% CHIP  pkg 0402LF  page 127 : A = P3V3_AUX ; B = RST_BMC_FROM_SWB_ISO_N
PC6015  Q_CAP  22UF 16V 20% X6S  pkg C0805  page 270 : A = SW_P12V_AUX_P1V2_AUX_FLT ; B = GND
R853  Q_RES  0 5% EMPTY  pkg 0402LF  page 345 : A = P1V8_CPU1_RT2_1A_1D ; B = P1V8_CPU1_RT2_1A

(kicad_pcb
	(version 20260206)
	(generator "pcbnew")
	(generator_version "10.0")
	(general
		(thickness 1.6)
		(legacy_teardrops no)
	)
	(paper "A4")
	(title_block
		(title "04192023_DAF0TMB3IC0_F0TG_MB_C_brd_V02_OCP.brd")
		(comment 1 "Grand Teton / footprints 2461-2463 of 8354")
	)
	(layers
		(0 "F.Cu" signal "TOP")
		(4 "In1.Cu" signal "GND")
		(6 "In2.Cu" signal "IN1")
		(8 "In3.Cu" signal "GND1")
		(10 "In4.Cu" signal "IN2")
		(12 "In5.Cu" signal "GND2")
		(14 "In6.Cu" signal "IN3")
		(16 "In7.Cu" signal "GND3")
		(18 "In8.Cu" signal "VCC")
		(20 "In9.Cu" signal "VCC1")
		(22 "In10.Cu" signal "GND4")
		(24 "In11.Cu" signal "IN4")
		(26 "In12.Cu" signal "GND5")
		(28 "In13.Cu" signal "IN5")
		(30 "In14.Cu" signal "GND6")
		(32 "In15.Cu" signal "IN6")
		(34 "In16.Cu" signal "GND7")
		(2 "B.Cu" signal "BOTTOM")
		(9 "F.Adhes" user "F.Adhesive")
		(11 "B.Adhes" user "B.Adhesive")
		(13 "F.Paste" user "Package Geometry/Pastemask Top")
		(15 "B.Paste" user "Package Geometry/Pastemask Bottom")
		(5 "F.SilkS" user "Ref Des/Silkscreen Top")
		(7 "B.SilkS" user "Ref Des/Silkscreen Bottom")
		(1 "F.Mask" user "Board Geometry/Soldermask Top")
		(3 "B.Mask" user "Board Geometry/Soldermask Bottom")
		(17 "Dwgs.User" user "User.Drawings")
		(19 "Cmts.User" user "User.Comments")
		(21 "Eco1.User" user "User.Eco1")
		(23 "Eco2.User" user "User.Eco2")
		(25 "Edge.Cuts" user "Board Geometry/Outline")
		(27 "Margin" user)
		(31 "F.CrtYd" user "Package Geometry/Place Bound Top")
		(29 "B.CrtYd" user "Package Geometry/Place Bound Bottom")
		(35 "F.Fab" user "Ref Des/Assembly Top")
		(33 "B.Fab" user "Ref Des/Assembly Bottom")
	)
	(footprint ""
		(layer "F.Cu")
		(at 419.230302 -438.234836 90)
		(property "Reference" "R2919"
			(at 0 0 90)
			(layer "F.SilkS")
			(hide yes)
			(effects
				(font
					(size 1.27 1.27)
				)
			)
		)
		(property "Value" ""
			(at 0 0 90)
			(layer "F.Fab")
			(effects
				(font
					(size 1.27 1.27)
				)
			)
		)
		(duplicate_pad_numbers_are_jumpers no)
		(fp_line
			(start 0.7874 -0.4064)
			(end 0.7874 0.4064)
			(stroke
				(width 0.1524)
				(type default)
			)
			(layer "F.SilkS")
		)
		(fp_line
			(start -0.7874 -0.4064)
			(end 0.7874 -0.4064)
			(stroke
				(width 0.1524)
				(type default)
			)
			(layer "F.SilkS")
		)
		(fp_line
			(start 0.7874 0.4064)
			(end -0.7874 0.4064)
			(stroke
				(width 0.1524)
				(type default)
			)
			(layer "F.SilkS")
		)
		(fp_line
			(start -0.7874 0.4064)
			(end -0.7874 -0.4064)
			(stroke
				(width 0.1524)
				(type default)
			)
			(layer "F.SilkS")
		)
		(fp_line
			(start -0.12065 -0.305054)
			(end -0.12065 -0.2794)
			(stroke
				(width 0.1)
				(type default)
			)
			(layer "F.Fab")
		)
		(fp_line
			(start -0.67945 -0.305054)
			(end -0.12065 -0.305054)
			(stroke
				(width 0.1)
				(type default)
			)
			(layer "F.Fab")
		)
		(fp_line
			(start 0.67945 -0.3048)
			(end 0.67945 0.3048)
			(stroke
				(width 0.1)
				(type default)
			)
			(layer "F.Fab")
		)
		(fp_line
			(start 0.12065 -0.3048)
			(end 0.67945 -0.3048)
			(stroke
				(width 0.1)
				(type default)
			)
			(layer "F.Fab")
		)
		(fp_line
			(start 0.12065 -0.2794)
			(end 0.12065 -0.3048)
			(stroke
				(width 0.1)
				(type default)
			)
			(layer "F.Fab")
		)
		(fp_line
			(start -0.12065 -0.2794)
			(end 0.12065 -0.2794)
			(stroke
				(width 0.1)
				(type default)
			)
			(layer "F.Fab")
		)
		(fp_line
			(start 0.120396 0.2794)
			(end -0.12065 0.2794)
			(stroke
				(width 0.1)
				(type default)
			)
			(layer "F.Fab")
		)
		(fp_line
			(start -0.12065 0.2794)
			(end -0.12065 0.3048)
			(stroke
				(width 0.1)
				(type default)
			)
			(layer "F.Fab")
		)
		(fp_line
			(start 0.67945 0.3048)
			(end 0.120396 0.3048)
			(stroke
				(width 0.1)
				(type default)
			)
			(layer "F.Fab")
		)
		(fp_line
			(start 0.120396 0.3048)
			(end 0.120396 0.2794)
			(stroke
				(width 0.1)
				(type default)
			)
			(layer "F.Fab")
		)
		(fp_line
			(start -0.12065 0.3048)
			(end -0.67945 0.3048)
			(stroke
				(width 0.1)
				(type default)
			)
			(layer "F.Fab")
		)
		(fp_line
			(start -0.67945 0.3048)
			(end -0.67945 -0.305054)
			(stroke
				(width 0.1)
				(type default)
			)
			(layer "F.Fab")
		)
		(pad "1" smd circle
			(at -0.40005 0 90)
			(size 0 0)
			(layers "F.Cu" "F.Mask" "F.Paste")
			(net "P3V3_AUX")
		)
		(pad "2" smd circle
			(at 0.40005 0 90)
			(size 0 0)
			(layers "F.Cu" "F.Mask" "F.Paste")
			(net "RST_BMC_FROM_SWB_ISO_N")
		)
	)
	(footprint ""
		(layer "F.Cu")
		(at 170.46956 -388.753604 180)
		(property "Reference" "R853"
			(at 0 0 180)
			(layer "F.SilkS")
			(hide yes)
			(effects
				(font
					(size 1.27 1.27)
				)
			)
		)
		(property "Value" ""
			(at 0 0 180)
			(layer "F.Fab")
			(effects
				(font
					(size 1.27 1.27)
				)
			)
		)
		(duplicate_pad_numbers_are_jumpers no)
		(fp_line
			(start 0.7874 0.4064)
			(end -0.7874 0.4064)
			(stroke
				(width 0.1524)
				(type default)
			)
			(layer "F.SilkS")
		)
		(fp_line
			(start 0.7874 -0.4064)
			(end 0.7874 0.4064)
			(stroke
				(width 0.1524)
				(type default)
			)
			(layer "F.SilkS")
		)
		(fp_line
			(start -0.7874 0.4064)
			(end -0.7874 -0.4064)
			(stroke
				(width 0.1524)
				(type default)
			)
			(layer "F.SilkS")
		)
		(fp_line
			(start -0.7874 -0.4064)
			(end 0.7874 -0.4064)
			(stroke
				(width 0.1524)
				(type default)
			)
			(layer "F.SilkS")
		)
		(fp_line
			(start 0.67945 0.3048)
			(end 0.120396 0.3048)
			(stroke
				(width 0.1)
				(type default)
			)
			(layer "F.Fab")
		)
		(fp_line
			(start 0.67945 -0.3048)
			(end 0.67945 0.3048)
			(stroke
				(width 0.1)
				(type default)
			)
			(layer "F.Fab")
		)
		(fp_line
			(start 0.12065 -0.2794)
			(end 0.12065 -0.3048)
			(stroke
				(width 0.1)
				(type default)
			)
			(layer "F.Fab")
		)
		(fp_line
			(start 0.12065 -0.3048)
			(end 0.67945 -0.3048)
			(stroke
				(width 0.1)
				(type default)
			)
			(layer "F.Fab")
		)
		(fp_line
			(start 0.120396 0.3048)
			(end 0.120396 0.2794)
			(stroke
				(width 0.1)
				(type default)
			)
			(layer "F.Fab")
		)
		(fp_line
			(start 0.120396 0.2794)
			(end -0.12065 0.2794)
			(stroke
				(width 0.1)
				(type default)
			)
			(layer "F.Fab")
		)
		(fp_line
			(start -0.12065 0.3048)
			(end -0.67945 0.3048)
			(stroke
				(width 0.1)
				(type default)
			)
			(layer "F.Fab")
		)
		(fp_line
			(start -0.12065 0.2794)
			(end -0.12065 0.3048)
			(stroke
				(width 0.1)
				(type default)
			)
			(layer "F.Fab")
		)
		(fp_line
			(start -0.12065 -0.2794)
			(end 0.12065 -0.2794)
			(stroke
				(width 0.1)
				(type default)
			)
			(layer "F.Fab")
		)
		(fp_line
			(start -0.12065 -0.305054)
			(end -0.12065 -0.2794)
			(stroke
				(width 0.1)
				(type default)
			)
			(layer "F.Fab")
		)
		(fp_line
			(start -0.67945 0.3048)
			(end -0.67945 -0.305054)
			(stroke
				(width 0.1)
				(type default)
			)
			(layer "F.Fab")
		)
		(fp_line
			(start -0.67945 -0.305054)
			(end -0.12065 -0.305054)
			(stroke
				(width 0.1)
				(type default)
			)
			(layer "F.Fab")
		)
		(pad "1" smd rect
			(at -0.40005 0)
			(size 0.4572 0.508)
			(layers "F.Cu" "F.Mask" "F.Paste")
			(net "P1V8_CPU1_RT2_1A_1D")
		)
		(pad "2" smd rect
			(at 0.40005 0)
			(size 0.4572 0.508)
			(layers "F.Cu" "F.Mask" "F.Paste")
			(net "P1V8_CPU1_RT2_1A")
		)
	)
	(footprint ""
		(layer "F.Cu")
		(at 116.045234 -77.002894 90)
		(property "Reference" "PC6015"
			(at 0 0 90)
			(layer "F.SilkS")
			(hide yes)
			(effects
				(font
					(size 1.27 1.27)
				)
			)
		)
		(property "Value" ""
			(at 0 0 90)
			(layer "F.Fab")
			(effects
				(font
					(size 1.27 1.27)
				)
			)
		)
		(duplicate_pad_numbers_are_jumpers no)
		(fp_line
			(start 1.524 -0.762)
			(end 1.524 0.762)
			(stroke
				(width 0.1524)
				(type default)
			)
			(layer "F.SilkS")
		)
		(fp_line
			(start -1.524 -0.762)
			(end 1.524 -0.762)
			(stroke
				(width 0.1524)
				(type default)
			)
			(layer "F.SilkS")
		)
		(fp_line
			(start 1.524 0.762)
			(end -1.524 0.762)
			(stroke
				(width 0.1524)
				(type default)
			)
			(layer "F.SilkS")
		)
		(fp_line
			(start -1.524 0.762)
			(end -1.524 -0.762)
			(stroke
				(width 0.1524)
				(type default)
			)
			(layer "F.SilkS")
		)
		(fp_line
			(start 1.1049 -0.724916)
			(end -1.1049 -0.724916)
			(stroke
				(width 0.1)
				(type default)
			)
			(layer "F.Fab")
		)
		(fp_line
			(start -1.1049 -0.724916)
			(end -1.1049 0.724916)
			(stroke
				(width 0.1)
				(type default)
			)
			(layer "F.Fab")
		)
		(fp_line
			(start 1.1049 0.724916)
			(end 1.1049 -0.724916)
			(stroke
				(width 0.1)
				(type default)
			)
			(layer "F.Fab")
		)
		(fp_line
			(start -1.1049 0.724916)
			(end 1.1049 0.724916)
			(stroke
				(width 0.1)
				(type default)
			)
			(layer "F.Fab")
		)
		(pad "1" smd rect
			(at -0.889 0 270)
			(size 1.016 1.27)
			(layers "F.Cu" "F.Mask" "F.Paste")
			(net "SW_P12V_AUX_P1V2_AUX_FLT")
		)
		(pad "2" smd rect
			(at 0.889 0 270)
			(size 1.016 1.27)
			(layers "F.Cu" "F.Mask" "F.Paste")
			(net "GND")
		)
	)
)
